(kicad_pcb
	(version 20260206)
	(generator "pcbnew")
	(generator_version "10.0")
	(general
		(thickness 1.6)
		(legacy_teardrops no)
	)
	(paper "A4")
	(title_block
		(title "01162023_DA0F0TEBIF0_F0T_Expander_BD_F_brd_V02_OCP.brd")
		(comment 1 "Grand Teton / footprints 1749-1755 of 9728")
	)
	(layers
		(0 "F.Cu" signal "TOP")
		(4 "In1.Cu" signal "GND")
		(6 "In2.Cu" signal "VCC")
		(8 "In3.Cu" signal "VCC1")
		(10 "In4.Cu" signal "GND1")
		(12 "In5.Cu" signal "IN1")
		(14 "In6.Cu" signal "GND2")
		(16 "In7.Cu" signal "IN2")
		(18 "In8.Cu" signal "GND3")
		(20 "In9.Cu" signal "IN3")
		(22 "In10.Cu" signal "GND4")
		(24 "In11.Cu" signal "IN4")
		(26 "In12.Cu" signal "GND5")
		(28 "In13.Cu" signal "IN5")
		(30 "In14.Cu" signal "GND6")
		(32 "In15.Cu" signal "IN6")
		(34 "In16.Cu" signal "GND7")
		(2 "B.Cu" signal "BOTTOM")
		(9 "F.Adhes" user "F.Adhesive")
		(11 "B.Adhes" user "B.Adhesive")
		(13 "F.Paste" user "Package Geometry/Pastemask Top")
		(15 "B.Paste" user "Package Geometry/Pastemask Bottom")
		(5 "F.SilkS" user "Ref Des/Silkscreen Top")
		(7 "B.SilkS" user "Ref Des/Silkscreen Bottom")
		(1 "F.Mask" user "Board Geometry/Soldermask Top")
		(3 "B.Mask" user "Board Geometry/Soldermask Bottom")
		(17 "Dwgs.User" user "User.Drawings")
		(19 "Cmts.User" user "User.Comments")
		(21 "Eco1.User" user "User.Eco1")
		(23 "Eco2.User" user "User.Eco2")
		(25 "Edge.Cuts" user "Board Geometry/Outline")
		(27 "Margin" user)
		(31 "F.CrtYd" user "Package Geometry/Place Bound Top")
		(29 "B.CrtYd" user "Package Geometry/Place Bound Bottom")
		(35 "F.Fab" user "Ref Des/Assembly Top")
		(33 "B.Fab" user "Ref Des/Assembly Bottom")
	)
	(footprint ""
		(layer "F.Cu")
		(at 52.243736 -48.93691 180)
		(property "Reference" "R523"
			(at 0 0 180)
			(layer "F.SilkS")
			(hide yes)
			(effects
				(font
					(size 1.27 1.27)
				)
			)
		)
		(property "Value" ""
			(at 0 0 180)
			(layer "F.Fab")
			(effects
				(font
					(size 1.27 1.27)
				)
			)
		)
		(duplicate_pad_numbers_are_jumpers no)
		(fp_line
			(start 0.7874 0.4064)
			(end -0.7874 0.4064)
			(stroke
				(width 0.1524)
				(type default)
			)
			(layer "F.SilkS")
		)
		(fp_line
			(start 0.7874 -0.4064)
			(end 0.7874 0.4064)
			(stroke
				(width 0.1524)
				(type default)
			)
			(layer "F.SilkS")
		)
		(fp_line
			(start -0.7874 0.4064)
			(end -0.7874 -0.4064)
			(stroke
				(width 0.1524)
				(type default)
			)
			(layer "F.SilkS")
		)
		(fp_line
			(start -0.7874 -0.4064)
			(end 0.7874 -0.4064)
			(stroke
				(width 0.1524)
				(type default)
			)
			(layer "F.SilkS")
		)
		(fp_line
			(start 0.67945 0.3048)
			(end 0.120396 0.3048)
			(stroke
				(width 0.1)
				(type default)
			)
			(layer "F.Fab")
		)
		(fp_line
			(start 0.67945 -0.3048)
			(end 0.67945 0.3048)
			(stroke
				(width 0.1)
				(type default)
			)
			(layer "F.Fab")
		)
		(fp_line
			(start 0.12065 -0.2794)
			(end 0.12065 -0.3048)
			(stroke
				(width 0.1)
				(type default)
			)
			(layer "F.Fab")
		)
		(fp_line
			(start 0.12065 -0.3048)
			(end 0.67945 -0.3048)
			(stroke
				(width 0.1)
				(type default)
			)
			(layer "F.Fab")
		)
		(fp_line
			(start 0.120396 0.3048)
			(end 0.120396 0.2794)
			(stroke
				(width 0.1)
				(type default)
			)
			(layer "F.Fab")
		)
		(fp_line
			(start 0.120396 0.2794)
			(end -0.12065 0.2794)
			(stroke
				(width 0.1)
				(type default)
			)
			(layer "F.Fab")
		)
		(fp_line
			(start -0.12065 0.3048)
			(end -0.67945 0.3048)
			(stroke
				(width 0.1)
				(type default)
			)
			(layer "F.Fab")
		)
		(fp_line
			(start -0.12065 0.2794)
			(end -0.12065 0.3048)
			(stroke
				(width 0.1)
				(type default)
			)
			(layer "F.Fab")
		)
		(fp_line
			(start -0.12065 -0.2794)
			(end 0.12065 -0.2794)
			(stroke
				(width 0.1)
				(type default)
			)
			(layer "F.Fab")
		)
		(fp_line
			(start -0.12065 -0.305054)
			(end -0.12065 -0.2794)
			(stroke
				(width 0.1)
				(type default)
			)
			(layer "F.Fab")
		)
		(fp_line
			(start -0.67945 0.3048)
			(end -0.67945 -0.305054)
			(stroke
				(width 0.1)
				(type default)
			)
			(layer "F.Fab")
		)
		(fp_line
			(start -0.67945 -0.305054)
			(end -0.12065 -0.305054)
			(stroke
				(width 0.1)
				(type default)
			)
			(layer "F.Fab")
		)
		(pad "1" smd circle
			(at -0.40005 0 180)
			(size 0 0)
			(layers "F.Cu" "F.Mask" "F.Paste")
			(net "SMB_BIC_I2C6_MUX_SSD_0_7_ADC_R_SDA")
		)
		(pad "2" smd circle
			(at 0.40005 0 180)
			(size 0 0)
			(layers "F.Cu" "F.Mask" "F.Paste")
			(net "SMB_SSD1_ADC_SDA")
		)
	)
	(footprint ""
		(layer "F.Cu")
		(at 204.591158 -83.659472)
		(property "Reference" "R4331"
			(at 0 0 0)
			(layer "F.SilkS")
			(hide yes)
			(effects
				(font
					(size 1.27 1.27)
				)
			)
		)
		(property "Value" ""
			(at 0 0 0)
			(layer "F.Fab")
			(effects
				(font
					(size 1.27 1.27)
				)
			)
		)
		(duplicate_pad_numbers_are_jumpers no)
		(fp_line
			(start -0.7874 -0.4064)
			(end 0.7874 -0.4064)
			(stroke
				(width 0.1524)
				(type default)
			)
			(layer "F.SilkS")
		)
		(fp_line
			(start -0.7874 0.4064)
			(end -0.7874 -0.4064)
			(stroke
				(width 0.1524)
				(type default)
			)
			(layer "F.SilkS")
		)
		(fp_line
			(start 0.7874 -0.4064)
			(end 0.7874 0.4064)
			(stroke
				(width 0.1524)
				(type default)
			)
			(layer "F.SilkS")
		)
		(fp_line
			(start 0.7874 0.4064)
			(end -0.7874 0.4064)
			(stroke
				(width 0.1524)
				(type default)
			)
			(layer "F.SilkS")
		)
		(fp_line
			(start -0.67945 -0.305054)
			(end -0.12065 -0.305054)
			(stroke
				(width 0.1)
				(type default)
			)
			(layer "F.Fab")
		)
		(fp_line
			(start -0.67945 0.3048)
			(end -0.67945 -0.305054)
			(stroke
				(width 0.1)
				(type default)
			)
			(layer "F.Fab")
		)
		(fp_line
			(start -0.12065 -0.305054)
			(end -0.12065 -0.2794)
			(stroke
				(width 0.1)
				(type default)
			)
			(layer "F.Fab")
		)
		(fp_line
			(start -0.12065 -0.2794)
			(end 0.12065 -0.2794)
			(stroke
				(width 0.1)
				(type default)
			)
			(layer "F.Fab")
		)
		(fp_line
			(start -0.12065 0.2794)
			(end -0.12065 0.3048)
			(stroke
				(width 0.1)
				(type default)
			)
			(layer "F.Fab")
		)
		(fp_line
			(start -0.12065 0.3048)
			(end -0.67945 0.3048)
			(stroke
				(width 0.1)
				(type default)
			)
			(layer "F.Fab")
		)
		(fp_line
			(start 0.120396 0.2794)
			(end -0.12065 0.2794)
			(stroke
				(width 0.1)
				(type default)
			)
			(layer "F.Fab")
		)
		(fp_line
			(start 0.120396 0.3048)
			(end 0.120396 0.2794)
			(stroke
				(width 0.1)
				(type default)
			)
			(layer "F.Fab")
		)
		(fp_line
			(start 0.12065 -0.3048)
			(end 0.67945 -0.3048)
			(stroke
				(width 0.1)
				(type default)
			)
			(layer "F.Fab")
		)
		(fp_line
			(start 0.12065 -0.2794)
			(end 0.12065 -0.3048)
			(stroke
				(width 0.1)
				(type default)
			)
			(layer "F.Fab")
		)
		(fp_line
			(start 0.67945 -0.3048)
			(end 0.67945 0.3048)
			(stroke
				(width 0.1)
				(type default)
			)
			(layer "F.Fab")
		)
		(fp_line
			(start 0.67945 0.3048)
			(end 0.120396 0.3048)
			(stroke
				(width 0.1)
				(type default)
			)
			(layer "F.Fab")
		)
		(pad "1" smd circle
			(at -0.40005 0)
			(size 0 0)
			(layers "F.Cu" "F.Mask" "F.Paste")
			(net "P3V3_AUX")
		)
		(pad "2" smd circle
			(at 0.40005 0)
			(size 0 0)
			(layers "F.Cu" "F.Mask" "F.Paste")
			(net "SSD1_LED_R")
		)
	)
	(footprint ""
		(layer "F.Cu")
		(at 41.984168 -356.244906 90)
		(property "Reference" "C170"
			(at 0 0 90)
			(layer "F.SilkS")
			(hide yes)
			(effects
				(font
					(size 1.27 1.27)
				)
			)
		)
		(property "Value" ""
			(at 0 0 90)
			(layer "F.Fab")
			(effects
				(font
					(size 1.27 1.27)
				)
			)
		)
		(duplicate_pad_numbers_are_jumpers no)
		(fp_line
			(start 0.299974 -0.150114)
			(end 0.299974 0.150114)
			(stroke
				(width 0.1)
				(type default)
			)
			(layer "F.Fab")
		)
		(fp_line
			(start -0.299974 -0.150114)
			(end 0.299974 -0.150114)
			(stroke
				(width 0.1)
				(type default)
			)
			(layer "F.Fab")
		)
		(fp_line
			(start 0.299974 0.150114)
			(end -0.299974 0.150114)
			(stroke
				(width 0.1)
				(type default)
			)
			(layer "F.Fab")
		)
		(fp_line
			(start -0.299974 0.150114)
			(end -0.299974 -0.150114)
			(stroke
				(width 0.1)
				(type default)
			)
			(layer "F.Fab")
		)
		(pad "1" smd rect
			(at -0.2667 0 90)
			(size 0.3048 0.381)
			(layers "F.Cu" "F.Mask" "F.Paste")
			(net "P5E_PEX0_STN7_TX_DN<123>")
		)
		(pad "2" smd rect
			(at 0.2667 0 90)
			(size 0.3048 0.381)
			(layers "F.Cu" "F.Mask" "F.Paste")
			(net "P5E_PEX0_STN7_TX_C_DN<123>")
		)
	)
	(footprint ""
		(layer "F.Cu")
		(at 284.443678 -45.88891)
		(property "Reference" "R609"
			(at 0 0 0)
			(layer "F.SilkS")
			(hide yes)
			(effects
				(font
					(size 1.27 1.27)
				)
			)
		)
		(property "Value" ""
			(at 0 0 0)
			(layer "F.Fab")
			(effects
				(font
					(size 1.27 1.27)
				)
			)
		)
		(duplicate_pad_numbers_are_jumpers no)
		(fp_line
			(start -0.7874 -0.4064)
			(end 0.7874 -0.4064)
			(stroke
				(width 0.1524)
				(type default)
			)
			(layer "F.SilkS")
		)
		(fp_line
			(start -0.7874 0.4064)
			(end -0.7874 -0.4064)
			(stroke
				(width 0.1524)
				(type default)
			)
			(layer "F.SilkS")
		)
		(fp_line
			(start 0.7874 -0.4064)
			(end 0.7874 0.4064)
			(stroke
				(width 0.1524)
				(type default)
			)
			(layer "F.SilkS")
		)
		(fp_line
			(start 0.7874 0.4064)
			(end -0.7874 0.4064)
			(stroke
				(width 0.1524)
				(type default)
			)
			(layer "F.SilkS")
		)
		(fp_line
			(start -0.67945 -0.305054)
			(end -0.12065 -0.305054)
			(stroke
				(width 0.1)
				(type default)
			)
			(layer "F.Fab")
		)
		(fp_line
			(start -0.67945 0.3048)
			(end -0.67945 -0.305054)
			(stroke
				(width 0.1)
				(type default)
			)
			(layer "F.Fab")
		)
		(fp_line
			(start -0.12065 -0.305054)
			(end -0.12065 -0.2794)
			(stroke
				(width 0.1)
				(type default)
			)
			(layer "F.Fab")
		)
		(fp_line
			(start -0.12065 -0.2794)
			(end 0.12065 -0.2794)
			(stroke
				(width 0.1)
				(type default)
			)
			(layer "F.Fab")
		)
		(fp_line
			(start -0.12065 0.2794)
			(end -0.12065 0.3048)
			(stroke
				(width 0.1)
				(type default)
			)
			(layer "F.Fab")
		)
		(fp_line
			(start -0.12065 0.3048)
			(end -0.67945 0.3048)
			(stroke
				(width 0.1)
				(type default)
			)
			(layer "F.Fab")
		)
		(fp_line
			(start 0.120396 0.2794)
			(end -0.12065 0.2794)
			(stroke
				(width 0.1)
				(type default)
			)
			(layer "F.Fab")
		)
		(fp_line
			(start 0.120396 0.3048)
			(end 0.120396 0.2794)
			(stroke
				(width 0.1)
				(type default)
			)
			(layer "F.Fab")
		)
		(fp_line
			(start 0.12065 -0.3048)
			(end 0.67945 -0.3048)
			(stroke
				(width 0.1)
				(type default)
			)
			(layer "F.Fab")
		)
		(fp_line
			(start 0.12065 -0.2794)
			(end 0.12065 -0.3048)
			(stroke
				(width 0.1)
				(type default)
			)
			(layer "F.Fab")
		)
		(fp_line
			(start 0.67945 -0.3048)
			(end 0.67945 0.3048)
			(stroke
				(width 0.1)
				(type default)
			)
			(layer "F.Fab")
		)
		(fp_line
			(start 0.67945 0.3048)
			(end 0.120396 0.3048)
			(stroke
				(width 0.1)
				(type default)
			)
			(layer "F.Fab")
		)
		(pad "1" smd circle
			(at -0.40005 0)
			(size 0 0)
			(layers "F.Cu" "F.Mask" "F.Paste")
			(net "SSD9_ADC_A0")
		)
		(pad "2" smd circle
			(at 0.40005 0)
			(size 0 0)
			(layers "F.Cu" "F.Mask" "F.Paste")
			(net "GND")
		)
	)
	(footprint ""
		(layer "F.Cu")
		(at 292.320472 -26.666444 -90)
		(property "Reference" "R4073"
			(at 0 0 270)
			(layer "F.SilkS")
			(hide yes)
			(effects
				(font
					(size 1.27 1.27)
				)
			)
		)
		(property "Value" ""
			(at 0 0 270)
			(layer "F.Fab")
			(effects
				(font
					(size 1.27 1.27)
				)
			)
		)
		(duplicate_pad_numbers_are_jumpers no)
		(fp_line
			(start -0.7874 0.4064)
			(end -0.7874 -0.4064)
			(stroke
				(width 0.1524)
				(type default)
			)
			(layer "F.SilkS")
		)
		(fp_line
			(start 0.7874 0.4064)
			(end -0.7874 0.4064)
			(stroke
				(width 0.1524)
				(type default)
			)
			(layer "F.SilkS")
		)
		(fp_line
			(start -0.7874 -0.4064)
			(end 0.7874 -0.4064)
			(stroke
				(width 0.1524)
				(type default)
			)
			(layer "F.SilkS")
		)
		(fp_line
			(start 0.7874 -0.4064)
			(end 0.7874 0.4064)
			(stroke
				(width 0.1524)
				(type default)
			)
			(layer "F.SilkS")
		)
		(fp_line
			(start -0.67945 0.3048)
			(end -0.67945 -0.305054)
			(stroke
				(width 0.1)
				(type default)
			)
			(layer "F.Fab")
		)
		(fp_line
			(start -0.12065 0.3048)
			(end -0.67945 0.3048)
			(stroke
				(width 0.1)
				(type default)
			)
			(layer "F.Fab")
		)
		(fp_line
			(start 0.120396 0.3048)
			(end 0.120396 0.2794)
			(stroke
				(width 0.1)
				(type default)
			)
			(layer "F.Fab")
		)
		(fp_line
			(start 0.67945 0.3048)
			(end 0.120396 0.3048)
			(stroke
				(width 0.1)
				(type default)
			)
			(layer "F.Fab")
		)
		(fp_line
			(start -0.12065 0.2794)
			(end -0.12065 0.3048)
			(stroke
				(width 0.1)
				(type default)
			)
			(layer "F.Fab")
		)
		(fp_line
			(start 0.120396 0.2794)
			(end -0.12065 0.2794)
			(stroke
				(width 0.1)
				(type default)
			)
			(layer "F.Fab")
		)
		(fp_line
			(start -0.12065 -0.2794)
			(end 0.12065 -0.2794)
			(stroke
				(width 0.1)
				(type default)
			)
			(layer "F.Fab")
		)
		(fp_line
			(start 0.12065 -0.2794)
			(end 0.12065 -0.3048)
			(stroke
				(width 0.1)
				(type default)
			)
			(layer "F.Fab")
		)
		(fp_line
			(start 0.12065 -0.3048)
			(end 0.67945 -0.3048)
			(stroke
				(width 0.1)
				(type default)
			)
			(layer "F.Fab")
		)
		(fp_line
			(start 0.67945 -0.3048)
			(end 0.67945 0.3048)
			(stroke
				(width 0.1)
				(type default)
			)
			(layer "F.Fab")
		)
		(fp_line
			(start -0.67945 -0.305054)
			(end -0.12065 -0.305054)
			(stroke
				(width 0.1)
				(type default)
			)
			(layer "F.Fab")
		)
		(fp_line
			(start -0.12065 -0.305054)
			(end -0.12065 -0.2794)
			(stroke
				(width 0.1)
				(type default)
			)
			(layer "F.Fab")
		)
		(pad "1" smd circle
			(at -0.40005 0 270)
			(size 0 0)
			(layers "F.Cu" "F.Mask" "F.Paste")
			(net "PRSNT_SSD10_R_N")
		)
		(pad "2" smd circle
			(at 0.40005 0 270)
			(size 0 0)
			(layers "F.Cu" "F.Mask" "F.Paste")
			(net "PRSNT_SSD10_N")
		)
	)
	(footprint ""
		(layer "F.Cu")
		(at 364.342934 -279.486868 -90)
		(property "Reference" "PR163"
			(at 0 0 270)
			(layer "F.SilkS")
			(hide yes)
			(effects
				(font
					(size 1.27 1.27)
				)
			)
		)
		(property "Value" ""
			(at 0 0 270)
			(layer "F.Fab")
			(effects
				(font
					(size 1.27 1.27)
				)
			)
		)
		(duplicate_pad_numbers_are_jumpers no)
		(fp_line
			(start -0.7874 0.4064)
			(end -0.7874 -0.4064)
			(stroke
				(width 0.1524)
				(type default)
			)
			(layer "F.SilkS")
		)
		(fp_line
			(start 0.7874 0.4064)
			(end -0.7874 0.4064)
			(stroke
				(width 0.1524)
				(type default)
			)
			(layer "F.SilkS")
		)
		(fp_line
			(start -0.7874 -0.4064)
			(end 0.7874 -0.4064)
			(stroke
				(width 0.1524)
				(type default)
			)
			(layer "F.SilkS")
		)
		(fp_line
			(start 0.7874 -0.4064)
			(end 0.7874 0.4064)
			(stroke
				(width 0.1524)
				(type default)
			)
			(layer "F.SilkS")
		)
		(fp_line
			(start -0.67945 0.3048)
			(end -0.67945 -0.305054)
			(stroke
				(width 0.1)
				(type default)
			)
			(layer "F.Fab")
		)
		(fp_line
			(start -0.12065 0.3048)
			(end -0.67945 0.3048)
			(stroke
				(width 0.1)
				(type default)
			)
			(layer "F.Fab")
		)
		(fp_line
			(start 0.120396 0.3048)
			(end 0.120396 0.2794)
			(stroke
				(width 0.1)
				(type default)
			)
			(layer "F.Fab")
		)
		(fp_line
			(start 0.67945 0.3048)
			(end 0.120396 0.3048)
			(stroke
				(width 0.1)
				(type default)
			)
			(layer "F.Fab")
		)
		(fp_line
			(start -0.12065 0.2794)
			(end -0.12065 0.3048)
			(stroke
				(width 0.1)
				(type default)
			)
			(layer "F.Fab")
		)
		(fp_line
			(start 0.120396 0.2794)
			(end -0.12065 0.2794)
			(stroke
				(width 0.1)
				(type default)
			)
			(layer "F.Fab")
		)
		(fp_line
			(start -0.12065 -0.2794)
			(end 0.12065 -0.2794)
			(stroke
				(width 0.1)
				(type default)
			)
			(layer "F.Fab")
		)
		(fp_line
			(start 0.12065 -0.2794)
			(end 0.12065 -0.3048)
			(stroke
				(width 0.1)
				(type default)
			)
			(layer "F.Fab")
		)
		(fp_line
			(start 0.12065 -0.3048)
			(end 0.67945 -0.3048)
			(stroke
				(width 0.1)
				(type default)
			)
			(layer "F.Fab")
		)
		(fp_line
			(start 0.67945 -0.3048)
			(end 0.67945 0.3048)
			(stroke
				(width 0.1)
				(type default)
			)
			(layer "F.Fab")
		)
		(fp_line
			(start -0.67945 -0.305054)
			(end -0.12065 -0.305054)
			(stroke
				(width 0.1)
				(type default)
			)
			(layer "F.Fab")
		)
		(fp_line
			(start -0.12065 -0.305054)
			(end -0.12065 -0.2794)
			(stroke
				(width 0.1)
				(type default)
			)
			(layer "F.Fab")
		)
		(pad "1" smd circle
			(at -0.40005 0 270)
			(size 0 0)
			(layers "F.Cu" "F.Mask" "F.Paste")
			(net "P0V8_PEX3_LSET2")
		)
		(pad "2" smd circle
			(at 0.40005 0 270)
			(size 0 0)
			(layers "F.Cu" "F.Mask" "F.Paste")
			(net "GND")
		)
	)
	(footprint ""
		(layer "F.Cu")
		(at 264.670286 -252.356874 -90)
		(property "Reference" "R1364"
			(at 0 0 270)
			(layer "F.SilkS")
			(hide yes)
			(effects
				(font
					(size 1.27 1.27)
				)
			)
		)
		(property "Value" ""
			(at 0 0 270)
			(layer "F.Fab")
			(effects
				(font
					(size 1.27 1.27)
				)
			)
		)
		(duplicate_pad_numbers_are_jumpers no)
		(fp_line
			(start -0.7874 0.4064)
			(end -0.7874 -0.4064)
			(stroke
				(width 0.1524)
				(type default)
			)
			(layer "F.SilkS")
		)
		(fp_line
			(start 0.7874 0.4064)
			(end -0.7874 0.4064)
			(stroke
				(width 0.1524)
				(type default)
			)
			(layer "F.SilkS")
		)
		(fp_line
			(start -0.7874 -0.4064)
			(end 0.7874 -0.4064)
			(stroke
				(width 0.1524)
				(type default)
			)
			(layer "F.SilkS")
		)
		(fp_line
			(start 0.7874 -0.4064)
			(end 0.7874 0.4064)
			(stroke
				(width 0.1524)
				(type default)
			)
			(layer "F.SilkS")
		)
		(fp_line
			(start -0.67945 0.3048)
			(end -0.67945 -0.305054)
			(stroke
				(width 0.1)
				(type default)
			)
			(layer "F.Fab")
		)
		(fp_line
			(start -0.12065 0.3048)
			(end -0.67945 0.3048)
			(stroke
				(width 0.1)
				(type default)
			)
			(layer "F.Fab")
		)
		(fp_line
			(start 0.120396 0.3048)
			(end 0.120396 0.2794)
			(stroke
				(width 0.1)
				(type default)
			)
			(layer "F.Fab")
		)
		(fp_line
			(start 0.67945 0.3048)
			(end 0.120396 0.3048)
			(stroke
				(width 0.1)
				(type default)
			)
			(layer "F.Fab")
		)
		(fp_line
			(start -0.12065 0.2794)
			(end -0.12065 0.3048)
			(stroke
				(width 0.1)
				(type default)
			)
			(layer "F.Fab")
		)
		(fp_line
			(start 0.120396 0.2794)
			(end -0.12065 0.2794)
			(stroke
				(width 0.1)
				(type default)
			)
			(layer "F.Fab")
		)
		(fp_line
			(start -0.12065 -0.2794)
			(end 0.12065 -0.2794)
			(stroke
				(width 0.1)
				(type default)
			)
			(layer "F.Fab")
		)
		(fp_line
			(start 0.12065 -0.2794)
			(end 0.12065 -0.3048)
			(stroke
				(width 0.1)
				(type default)
			)
			(layer "F.Fab")
		)
		(fp_line
			(start 0.12065 -0.3048)
			(end 0.67945 -0.3048)
			(stroke
				(width 0.1)
				(type default)
			)
			(layer "F.Fab")
		)
		(fp_line
			(start 0.67945 -0.3048)
			(end 0.67945 0.3048)
			(stroke
				(width 0.1)
				(type default)
			)
			(layer "F.Fab")
		)
		(fp_line
			(start -0.67945 -0.305054)
			(end -0.12065 -0.305054)
			(stroke
				(width 0.1)
				(type default)
			)
			(layer "F.Fab")
		)
		(fp_line
			(start -0.12065 -0.305054)
			(end -0.12065 -0.2794)
			(stroke
				(width 0.1)
				(type default)
			)
			(layer "F.Fab")
		)
		(pad "1" smd circle
			(at -0.40005 0 270)
			(size 0 0)
			(layers "F.Cu" "F.Mask" "F.Paste")
			(net "GND")
		)
		(pad "2" smd circle
			(at 0.40005 0 270)
			(size 0 0)
			(layers "F.Cu" "F.Mask" "F.Paste")
			(net "PEX2_MODE_SEL8")
		)
	)
)
